(kicad_pcb
	(version 20221018)
	(generator pcbnew)
	(general
    (thickness 1.656)
  )
	(paper "A4")
	(title_block
    (title "SDI-MIPI Bridge")
    (date "2023-08-09")
    (rev "1.3.4")
    (company "Antmicro")
		(comment 9 "footprints 21-30 of 190")
	)
	(layers
    (0 "F.Cu" signal)
    (1 "In1.Cu" power)
    (2 "In2.Cu" power)
    (3 "In3.Cu" signal)
    (4 "In4.Cu" signal)
    (31 "B.Cu" signal)
    (32 "B.Adhes" user "B.Adhesive")
    (33 "F.Adhes" user "F.Adhesive")
    (34 "B.Paste" user)
    (35 "F.Paste" user)
    (36 "B.SilkS" user "B.Silkscreen")
    (37 "F.SilkS" user "F.Silkscreen")
    (38 "B.Mask" user)
    (39 "F.Mask" user)
    (40 "Dwgs.User" user "User.Drawings")
    (41 "Cmts.User" user "User.Comments")
    (42 "Eco1.User" user "User.Eco1")
    (43 "Eco2.User" user "User.Eco2")
    (44 "Edge.Cuts" user)
    (45 "Margin" user)
    (46 "B.CrtYd" user "B.Courtyard")
    (47 "F.CrtYd" user "F.Courtyard")
    (48 "B.Fab" user)
    (49 "F.Fab" user)
  )
	(footprint "sdi-mipi-bridge-footprints:R_0402_1005Metric" (layer "F.Cu")
    (at 131 107.4 -90)
    (descr "Resistor SMD 0402")
    (tags "resistor SMD 0402")
    (property "Author" "Antmicro")
    (property "License" "Apache-2.0")
    (property "MPN" "CR0402-FX-1000GLF")
    (property "Manufacturer" "Bourns")
    (property "Sheetfile" "sdi-mipi-bridge.kicad_sch")
    (property "Sheetname" "")
    (property "Tolerance" "1%")
    (property "Val" "100R")
    (property "ki_description" "100R resistor in 0402 package with 1% tolerance")
    (attr smd)
    (fp_text reference "R88" (at 0.9 -3.3 -90) (layer "F.SilkS")
        (effects (font (size 0.65 0.65) (thickness 0.15)) (justify left bottom))
    )
    (fp_text value "R_100R_0402" (at 0 1.4 -90) (layer "F.Fab") hide
        (effects (font (size 0.7 0.7) (thickness 0.15)) (justify left bottom))
    )
    (fp_text user "Author: Antmicro" (at -0.95 4.169 -90) (layer "F.Fab") hide
        (effects (font (size 0.7 0.7) (thickness 0.15)) (justify left bottom))
    )
    (fp_text user "License: Apache-2.0" (at -0.95 5.169 -90) (layer "F.Fab") hide
        (effects (font (size 0.7 0.7) (thickness 0.15)) (justify left bottom))
    )
    (fp_text user "${REFERENCE}" (at -0.95 3.168 -90) (layer "F.Fab") hide
        (effects (font (size 0.7 0.7) (thickness 0.15)) (justify left bottom))
    )
    (fp_rect (start -0.93 -0.47) (end 0.93 0.47)
      (stroke (width 0.05) (type solid)) (fill none) (layer "F.CrtYd"))
    (fp_rect (start -0.5 -0.25) (end 0.5 0.25)
      (stroke (width 0.15) (type solid)) (fill none) (layer "F.Fab"))
    (pad "1" smd roundrect (at -0.485 0 270) (size 0.59 0.64) (layers "F.Cu" "F.Paste" "F.Mask") (roundrect_rratio 0.25)
      (net 86 "Net-(D2-Pad1)") (pintype "passive"))
    (pad "2" smd roundrect (at 0.485 0 270) (size 0.59 0.64) (layers "F.Cu" "F.Paste" "F.Mask") (roundrect_rratio 0.25)
      (net 88 "/CDONE") (pintype "passive"))
  )
	(footprint "sdi-mipi-bridge-footprints:C_0402_1005Metric" (layer "F.Cu")
    (at 117.5 106.4 90)
    (descr "Capacitor SMD 0402")
    (tags "capacitor SMD 0402")
    (property "Author" "Antmicro")
    (property "Dielectric" "")
    (property "License" "Apache-2.0")
    (property "MPN" "MC0402X473K160CT")
    (property "Manufacturer" "Multicomp")
    (property "Sheetfile" "sdi-mipi-bridge.kicad_sch")
    (property "Sheetname" "")
    (property "Val" "47n")
    (property "Voltage" "")
    (property "ki_description" " ")
    (attr smd)
    (fp_text reference "C63" (at -2.9 0.4 90) (layer "F.SilkS")
        (effects (font (size 0.65 0.65) (thickness 0.15)) (justify left bottom))
    )
    (fp_text value "C_47n_0402" (at 0 1.4 90) (layer "F.Fab") hide
        (effects (font (size 0.7 0.7) (thickness 0.15)) (justify left bottom))
    )
    (fp_text user "License: Apache-2.0" (at -0.932 5.17 90) (layer "F.Fab") hide
        (effects (font (size 0.7 0.7) (thickness 0.15)) (justify left bottom))
    )
    (fp_text user "${REFERENCE}" (at -0.932 3.168 90) (layer "F.Fab") hide
        (effects (font (size 0.7 0.7) (thickness 0.15)) (justify left bottom))
    )
    (fp_text user "Author: Antmicro" (at -0.932 4.17 90) (layer "F.Fab") hide
        (effects (font (size 0.7 0.7) (thickness 0.15)) (justify left bottom))
    )
    (fp_rect (start -0.94 -0.47) (end 0.94 0.47)
      (stroke (width 0.05) (type solid)) (fill none) (layer "F.CrtYd"))
    (fp_rect (start -0.499 -0.249) (end 0.499 0.249)
      (stroke (width 0.15) (type solid)) (fill none) (layer "F.Fab"))
    (pad "1" smd roundrect (at -0.484 0 90) (size 0.59 0.64) (layers "F.Cu" "F.Paste" "F.Mask") (roundrect_rratio 0.25)
      (net 10 "/LF") (pintype "passive"))
    (pad "2" smd roundrect (at 0.484 0 90) (size 0.59 0.64) (layers "F.Cu" "F.Paste" "F.Mask") (roundrect_rratio 0.25)
      (net 3 "GNDA") (pintype "passive"))
  )
	(footprint "sdi-mipi-bridge-footprints:LED_0603_1608Metric_G" (layer "F.Cu")
    (at 131 104.4 90)
    (descr "LED SMD 0603 Green")
    (tags "LED SMD 0603 Green")
    (property "Author" "Antmicro")
    (property "License" "Apache-2.0")
    (property "MPN" "LG L29K-G2J1-24-Z")
    (property "Manufacturer" "Osram")
    (property "Sheetfile" "sdi-mipi-bridge.kicad_sch")
    (property "Sheetname" "")
    (attr smd)
    (fp_text reference "D2" (at 0.2 -0.7 90) (layer "F.SilkS")
        (effects (font (size 0.65 0.65) (thickness 0.15)) (justify left bottom))
    )
    (fp_text value "LED_G_0603_LG_L29K-G2J1-24-Z" (at 0 1.6 90) (layer "F.Fab") hide
        (effects (font (size 0.7 0.7) (thickness 0.15)) (justify left bottom))
    )
    (fp_text user "License: Apache-2.0" (at -1.31 5.769 90) (layer "F.Fab") hide
        (effects (font (size 0.7 0.7) (thickness 0.15)) (justify left bottom))
    )
    (fp_text user "Author: Antmicro" (at -1.31 4.769 90) (layer "F.Fab") hide
        (effects (font (size 0.7 0.7) (thickness 0.15)) (justify left bottom))
    )
    (fp_text user "${REFERENCE}" (at -1.31 3.769 90) (layer "F.Fab") hide
        (effects (font (size 0.7 0.7) (thickness 0.15)) (justify left bottom))
    )
    (fp_line (start -0.27 -0.35) (end 0.27 -0.35)
      (stroke (width 0.15) (type solid)) (layer "F.SilkS"))
    (fp_line (start -0.27 0.351) (end 0.27 0.351)
      (stroke (width 0.15) (type solid)) (layer "F.SilkS"))
    (fp_line (start -0.106328 -0.200008) (end -0.106328 0.199992)
      (stroke (width 0.1) (type solid)) (layer "F.SilkS"))
    (fp_line (start -0.106328 -0.200008) (end 0.093672 -0.000008)
      (stroke (width 0.1) (type solid)) (layer "F.SilkS"))
    (fp_line (start -0.106328 -0.000008) (end -0.29 0)
      (stroke (width 0.1) (type solid)) (layer "F.SilkS"))
    (fp_line (start 0.093672 -0.200008) (end 0.093672 0.199992)
      (stroke (width 0.1) (type solid)) (layer "F.SilkS"))
    (fp_line (start 0.093672 -0.000008) (end -0.106328 0.199992)
      (stroke (width 0.1) (type solid)) (layer "F.SilkS"))
    (fp_line (start 0.093672 -0.000008) (end 0.293672 -0.000008)
      (stroke (width 0.1) (type solid)) (layer "F.SilkS"))
    (fp_line (start 1.25 0.32) (end 1.25 -0.32)
      (stroke (width 0.15) (type solid)) (layer "F.SilkS"))
    (fp_rect (start 1.26 0.65) (end -1.26 -0.65)
      (stroke (width 0.05) (type solid)) (fill none) (layer "F.CrtYd"))
    (fp_line (start -0.599 0) (end -0.201 0)
      (stroke (width 0.15) (type solid)) (layer "F.Fab"))
    (fp_line (start -0.201 -0.2) (end -0.201 0)
      (stroke (width 0.15) (type solid)) (layer "F.Fab"))
    (fp_line (start -0.201 0) (end -0.201 0.202)
      (stroke (width 0.15) (type solid)) (layer "F.Fab"))
    (fp_line (start -0.201 0.202) (end 0.101 0)
      (stroke (width 0.15) (type solid)) (layer "F.Fab"))
    (fp_line (start 0.101 0) (end -0.201 -0.2)
      (stroke (width 0.15) (type solid)) (layer "F.Fab"))
    (fp_line (start 0.199 -0.2) (end 0.199 -0.1)
      (stroke (width 0.15) (type solid)) (layer "F.Fab"))
    (fp_line (start 0.199 0) (end 0.597 0)
      (stroke (width 0.15) (type solid)) (layer "F.Fab"))
    (fp_line (start 0.199 0.202) (end 0.199 -0.1)
      (stroke (width 0.15) (type solid)) (layer "F.Fab"))
    (fp_rect (start -0.848 -0.4) (end 0.85 0.402)
      (stroke (width 0.15) (type solid)) (fill none) (layer "F.Fab"))
    (pad "1" smd rect (at -0.75 0 270) (size 0.8 0.8) (layers "F.Cu" "F.Paste" "F.Mask")
      (net 86 "Net-(D2-Pad1)") (pintype "passive"))
    (pad "2" smd rect (at 0.75 0 270) (size 0.8 0.8) (layers "F.Cu" "F.Paste" "F.Mask")
      (net 1 "GNDREF") (pinfunction "2") (pintype "passive"))
  )
	(footprint "sdi-mipi-bridge-footprints:Testpoint_smd_1mm" (layer "F.Cu")
    (at 122.5125 97.0398)
    (property "Author" "Antmicro")
    (property "License" "Apache-2.0")
    (property "MPN" "")
    (property "Manufacturer" "")
    (property "Sheetfile" "sdi-mipi-bridge.kicad_sch")
    (property "Sheetname" "")
    (property "ki_description" "Test Point 1mm")
    (attr smd)
    (fp_text reference "TP19" (at 0.2875 3.3602 90) (layer "F.SilkS")
        (effects (font (size 0.65 0.65) (thickness 0.15)) (justify left bottom))
    )
    (fp_text value "TP_1mm_SMD" (at 0 1.4) (layer "F.Fab") hide
        (effects (font (size 0.7 0.7) (thickness 0.15)) (justify left bottom))
    )
    (fp_text user "License: Apache-2.0" (at -0.5 5.2) (layer "F.Fab") hide
        (effects (font (size 0.7 0.7) (thickness 0.15)) (justify left bottom))
    )
    (fp_text user "${REFERENCE}" (at -0.5 2.8) (layer "F.Fab") hide
        (effects (font (size 0.7 0.7) (thickness 0.15)) (justify left bottom))
    )
    (fp_text user "Author: Antmicro" (at -0.5 4) (layer "F.Fab") hide
        (effects (font (size 0.7 0.7) (thickness 0.15)) (justify left bottom))
    )
    (pad "1" smd circle (at 0 0) (size 1 1) (layers "F.Cu" "F.Mask")
      (net 19 "/F_DE") (pinfunction "1") (pintype "passive"))
  )
	(footprint "sdi-mipi-bridge-footprints:Testpoint_smd_1mm" (layer "F.Cu")
    (at 124.329 97.0398)
    (property "Author" "Antmicro")
    (property "License" "Apache-2.0")
    (property "MPN" "")
    (property "Manufacturer" "")
    (property "Sheetfile" "sdi-mipi-bridge.kicad_sch")
    (property "Sheetname" "")
    (property "ki_description" "Test Point 1mm")
    (attr smd)
    (fp_text reference "TP20" (at 0.271 3.3602 90) (layer "F.SilkS")
        (effects (font (size 0.65 0.65) (thickness 0.15)) (justify left bottom))
    )
    (fp_text value "TP_1mm_SMD" (at 0 1.4) (layer "F.Fab") hide
        (effects (font (size 0.7 0.7) (thickness 0.15)) (justify left bottom))
    )
    (fp_text user "Author: Antmicro" (at -0.5 4) (layer "F.Fab") hide
        (effects (font (size 0.7 0.7) (thickness 0.15)) (justify left bottom))
    )
    (fp_text user "${REFERENCE}" (at -0.5 2.8) (layer "F.Fab") hide
        (effects (font (size 0.7 0.7) (thickness 0.15)) (justify left bottom))
    )
    (fp_text user "License: Apache-2.0" (at -0.5 5.2) (layer "F.Fab") hide
        (effects (font (size 0.7 0.7) (thickness 0.15)) (justify left bottom))
    )
    (pad "1" smd circle (at 0 0) (size 1 1) (layers "F.Cu" "F.Mask")
      (net 20 "/LOCKED") (pinfunction "1") (pintype "passive"))
  )
	(footprint "sdi-mipi-bridge-footprints:Testpoint_smd_1mm" (layer "F.Cu")
    (at 120.696 97.0398)
    (property "Author" "Antmicro")
    (property "License" "Apache-2.0")
    (property "MPN" "")
    (property "Manufacturer" "")
    (property "Sheetfile" "sdi-mipi-bridge.kicad_sch")
    (property "Sheetname" "")
    (property "ki_description" "Test Point 1mm")
    (attr smd)
    (fp_text reference "TP21" (at 0.304 3.3602 90) (layer "F.SilkS")
        (effects (font (size 0.65 0.65) (thickness 0.15)) (justify left bottom))
    )
    (fp_text value "TP_1mm_SMD" (at 0 1.4) (layer "F.Fab") hide
        (effects (font (size 0.7 0.7) (thickness 0.15)) (justify left bottom))
    )
    (fp_text user "${REFERENCE}" (at -0.5 2.8) (layer "F.Fab") hide
        (effects (font (size 0.7 0.7) (thickness 0.15)) (justify left bottom))
    )
    (fp_text user "Author: Antmicro" (at -0.5 4) (layer "F.Fab") hide
        (effects (font (size 0.7 0.7) (thickness 0.15)) (justify left bottom))
    )
    (fp_text user "License: Apache-2.0" (at -0.5 5.2) (layer "F.Fab") hide
        (effects (font (size 0.7 0.7) (thickness 0.15)) (justify left bottom))
    )
    (pad "1" smd circle (at 0 0) (size 1 1) (layers "F.Cu" "F.Mask")
      (net 21 "/Y_1ANC") (pinfunction "1") (pintype "passive"))
  )
	(footprint "sdi-mipi-bridge-footprints:Testpoint_smd_1mm" (layer "F.Cu")
    (at 131.6108 135.99 90)
    (property "Author" "Antmicro")
    (property "License" "Apache-2.0")
    (property "MPN" "")
    (property "Manufacturer" "")
    (property "Sheetfile" "sdi-mipi-bridge.kicad_sch")
    (property "Sheetname" "")
    (property "ki_description" "Test Point 1mm")
    (attr smd)
    (fp_text reference "TP6" (at -0.41 0.6892 180) (layer "F.SilkS")
        (effects (font (size 0.65 0.65) (thickness 0.15)) (justify left bottom))
    )
    (fp_text value "TP_1mm_SMD" (at 0 1.4 90) (layer "F.Fab") hide
        (effects (font (size 0.7 0.7) (thickness 0.15)) (justify left bottom))
    )
    (fp_text user "Author: Antmicro" (at -0.5 4 90) (layer "F.Fab") hide
        (effects (font (size 0.7 0.7) (thickness 0.15)) (justify left bottom))
    )
    (fp_text user "License: Apache-2.0" (at -0.5 5.2 90) (layer "F.Fab") hide
        (effects (font (size 0.7 0.7) (thickness 0.15)) (justify left bottom))
    )
    (fp_text user "${REFERENCE}" (at -0.5 2.8 90) (layer "F.Fab") hide
        (effects (font (size 0.7 0.7) (thickness 0.15)) (justify left bottom))
    )
    (pad "1" smd circle (at 0 0 90) (size 1 1) (layers "F.Cu" "F.Mask")
      (net 129 "Net-(U1-~{POK})") (pinfunction "1") (pintype "passive"))
  )
	(footprint "sdi-mipi-bridge-footprints:R_0402_1005Metric" (layer "F.Cu")
    (at 156.945 112.5 180)
    (descr "Resistor SMD 0402")
    (tags "resistor SMD 0402")
    (property "Author" "Antmicro")
    (property "Current" "1A")
    (property "License" "Apache-2.0")
    (property "MPN" "ERJ2GE0R00X")
    (property "Manufacturer" "Panasonic")
    (property "Sheetfile" "sdi-mipi-bridge.kicad_sch")
    (property "Sheetname" "")
    (property "Tolerance" "")
    (property "Val" "0R")
    (property "ki_description" "0R resistor in 0402 package with unspecified tolerance")
    (attr smd)
    (fp_text reference "R39" (at -2.955 -0.4) (layer "F.SilkS")
        (effects (font (size 0.65 0.65) (thickness 0.15)) (justify right bottom))
    )
    (fp_text value "R_0R_0402" (at 0 1.4) (layer "F.Fab") hide
        (effects (font (size 0.7 0.7) (thickness 0.15)) (justify right bottom))
    )
    (fp_text user "Author: Antmicro" (at -0.95 4.169) (layer "F.Fab") hide
        (effects (font (size 0.7 0.7) (thickness 0.15)) (justify right bottom))
    )
    (fp_text user "${REFERENCE}" (at -0.95 3.168) (layer "F.Fab") hide
        (effects (font (size 0.7 0.7) (thickness 0.15)) (justify right bottom))
    )
    (fp_text user "License: Apache-2.0" (at -0.95 5.169) (layer "F.Fab") hide
        (effects (font (size 0.7 0.7) (thickness 0.15)) (justify right bottom))
    )
    (fp_rect (start -0.93 -0.47) (end 0.93 0.47)
      (stroke (width 0.05) (type solid)) (fill none) (layer "F.CrtYd"))
    (fp_rect (start -0.5 -0.25) (end 0.5 0.25)
      (stroke (width 0.15) (type solid)) (fill none) (layer "F.Fab"))
    (pad "1" smd roundrect (at -0.485 0 180) (size 0.59 0.64) (layers "F.Cu" "F.Paste" "F.Mask") (roundrect_rratio 0.25)
      (net 83 "/SDA1") (pintype "passive"))
    (pad "2" smd roundrect (at 0.485 0 180) (size 0.59 0.64) (layers "F.Cu" "F.Paste" "F.Mask") (roundrect_rratio 0.25)
      (net 62 "/SDA_GS") (pintype "passive"))
  )
	(footprint "sdi-mipi-bridge-footprints:C_0402_1005Metric" (layer "F.Cu")
    (at 113.83 112.9)
    (descr "Capacitor SMD 0402")
    (tags "capacitor SMD 0402")
    (property "Author" "Antmicro")
    (property "Dielectric" "")
    (property "License" "Apache-2.0")
    (property "MPN" "C1005X6S1A105K050BC")
    (property "Manufacturer" "TDK")
    (property "Sheetfile" "sdi-mipi-bridge.kicad_sch")
    (property "Sheetname" "")
    (property "Val" "1u")
    (property "Voltage" "")
    (property "ki_description" " ")
    (attr smd)
    (fp_text reference "C55" (at -7.23 -0.925) (layer "F.SilkS")
        (effects (font (size 0.65 0.65) (thickness 0.15)) (justify left bottom))
    )
    (fp_text value "C_1u_0402" (at 0 1.4) (layer "F.Fab") hide
        (effects (font (size 0.7 0.7) (thickness 0.15)) (justify left bottom))
    )
    (fp_text user "License: Apache-2.0" (at -0.932 5.17) (layer "F.Fab") hide
        (effects (font (size 0.7 0.7) (thickness 0.15)) (justify left bottom))
    )
    (fp_text user "Author: Antmicro" (at -0.932 4.17) (layer "F.Fab") hide
        (effects (font (size 0.7 0.7) (thickness 0.15)) (justify left bottom))
    )
    (fp_text user "${REFERENCE}" (at -0.932 3.168) (layer "F.Fab") hide
        (effects (font (size 0.7 0.7) (thickness 0.15)) (justify left bottom))
    )
    (fp_rect (start -0.94 -0.47) (end 0.94 0.47)
      (stroke (width 0.05) (type solid)) (fill none) (layer "F.CrtYd"))
    (fp_rect (start -0.499 -0.249) (end 0.499 0.249)
      (stroke (width 0.15) (type solid)) (fill none) (layer "F.Fab"))
    (pad "1" smd roundrect (at -0.484 0) (size 0.59 0.64) (layers "F.Cu" "F.Paste" "F.Mask") (roundrect_rratio 0.25)
      (net 70 "Net-(C43-Pad2)") (pintype "passive"))
    (pad "2" smd roundrect (at 0.484 0) (size 0.59 0.64) (layers "F.Cu" "F.Paste" "F.Mask") (roundrect_rratio 0.25)
      (net 90 "/SDI_P") (pintype "passive"))
  )
	(footprint "sdi-mipi-bridge-footprints:R_0603_1608Metric" (layer "F.Cu")
    (at 111.47 112.2 90)
    (descr "Resistor SMD 0603")
    (tags "resistor SMD 0603")
    (property "Author" "Antmicro")
    (property "License" "Apache-2.0")
    (property "MPN" "CR0603-FX-75R0ELF")
    (property "Manufacturer" "Bourns")
    (property "Sheetfile" "sdi-mipi-bridge.kicad_sch")
    (property "Sheetname" "")
    (property "Tolerance" "1%")
    (property "Val" "75R")
    (property "ki_description" "75R resistor in 0603 package with 1% tolerance")
    (attr smd)
    (fp_text reference "R27" (at 3.4 0.33 270) (layer "F.SilkS")
        (effects (font (size 0.65 0.65) (thickness 0.15)) (justify right bottom))
    )
    (fp_text value "R_75R_0603" (at 0 1.6 90) (layer "F.Fab") hide
        (effects (font (size 0.7 0.7) (thickness 0.15)) (justify left bottom))
    )
    (fp_text user "Author: Antmicro" (at -1.25 4.9 90) (layer "F.Fab") hide
        (effects (font (size 0.7 0.7) (thickness 0.15)) (justify left bottom))
    )
    (fp_text user "${REFERENCE}" (at -1.25 3.898 90) (layer "F.Fab") hide
        (effects (font (size 0.7 0.7) (thickness 0.15)) (justify left bottom))
    )
    (fp_text user "License: Apache-2.0" (at -1.25 5.9 90) (layer "F.Fab") hide
        (effects (font (size 0.7 0.7) (thickness 0.15)) (justify left bottom))
    )
    (fp_line (start -0.3 -0.3) (end 0.3 -0.3)
      (stroke (width 0.15) (type solid)) (layer "F.SilkS"))
    (fp_line (start -0.3 0.3) (end 0.3 0.3)
      (stroke (width 0.15) (type solid)) (layer "F.SilkS"))
    (fp_rect (start -1.25 -0.7) (end 1.25 0.7)
      (stroke (width 0.05) (type solid)) (fill none) (layer "F.CrtYd"))
    (fp_rect (start -0.8 -0.4) (end 0.8 0.4)
      (stroke (width 0.15) (type solid)) (fill none) (layer "F.Fab"))
    (pad "1" smd roundrect (at -0.7 0 90) (size 0.6 0.8) (layers "F.Cu" "F.Paste" "F.Mask") (roundrect_rratio 0.2)
      (net 70 "Net-(C43-Pad2)") (pintype "passive"))
    (pad "2" smd roundrect (at 0.7 0 90) (size 0.6 0.8) (layers "F.Cu" "F.Paste" "F.Mask") (roundrect_rratio 0.2)
      (net 69 "Net-(C43-Pad1)") (pintype "passive"))
  )
)
